(kicad_pcb
	(version 20240108)
	(generator "pcbnew")
	(generator_version "8.0")
	(general
		(thickness 1.62)
		(legacy_teardrops no)
	)
	(paper "A4")
	(title_block
		(title "Jetson Orin Baseboard")
		(date "2025-03-12")
		(rev "1.3.4")
		(company "Antmicro Ltd")
		(comment 1 "www.antmicro.com")
		(comment 9 "footprints 119-120 of 677")
	)
	(layers
		(0 "F.Cu" signal)
		(1 "In1.Cu" signal)
		(2 "In2.Cu" signal)
		(3 "In3.Cu" signal)
		(4 "In4.Cu" jumper)
		(5 "In5.Cu" signal)
		(6 "In6.Cu" signal)
		(31 "B.Cu" signal)
		(32 "B.Adhes" user "B.Adhesive")
		(33 "F.Adhes" user "F.Adhesive")
		(34 "B.Paste" user)
		(35 "F.Paste" user)
		(36 "B.SilkS" user "B.Silkscreen")
		(37 "F.SilkS" user "F.Silkscreen")
		(38 "B.Mask" user)
		(39 "F.Mask" user)
		(40 "Dwgs.User" user "User.Drawings")
		(41 "Cmts.User" user "User.Comments")
		(42 "Eco1.User" user "User.Eco1")
		(43 "Eco2.User" user "User.Eco2")
		(44 "Edge.Cuts" user)
		(45 "Margin" user)
		(46 "B.CrtYd" user "B.Courtyard")
		(47 "F.CrtYd" user "F.Courtyard")
		(48 "B.Fab" user)
		(49 "F.Fab" user)
	)
	(footprint "antmicro-footprints:MLP44-24L_4x4x0.75mm"
		(layer "F.Cu")
		(at 62.67 97.435 -90)
		(property "Reference" "U1"
			(at 1.015 -4.02 0)
			(layer "F.SilkS")
			(effects
				(font
					(size 0.7 0.7)
					(thickness 0.15)
				)
				(justify left bottom)
			)
		)
		(property "Value" "SIC431AED-T1-GE3"
			(at 0 3.6 90)
			(layer "F.Fab")
			(effects
				(font
					(size 0.7 0.7)
					(thickness 0.15)
				)
				(justify right bottom)
			)
		)
		(property "Footprint" "antmicro-footprints:MLP44-24L_4x4x0.75mm"
			(at 0 0 -90)
			(layer "F.Fab")
			(hide yes)
			(effects
				(font
					(size 1.27 1.27)
					(thickness 0.15)
				)
			)
		)
		(property "Datasheet" "https://www.vishay.com/docs/74589/sic431.pdf"
			(at 0 0 -90)
			(layer "F.Fab")
			(hide yes)
			(effects
				(font
					(size 1.27 1.27)
					(thickness 0.15)
				)
			)
		)
		(property "Author" "Antmicro"
			(at -34.765 160.105 0)
			(layer "F.Fab")
			(hide yes)
			(effects
				(font
					(size 1 1)
					(thickness 0.15)
				)
			)
		)
		(property "License" "Apache-2.0"
			(at -34.765 160.105 0)
			(layer "F.Fab")
			(hide yes)
			(effects
				(font
					(size 1 1)
					(thickness 0.15)
				)
			)
		)
		(property "MPN" "SIC431AED-T1-GE3 "
			(at -34.765 160.105 0)
			(layer "F.Fab")
			(hide yes)
			(effects
				(font
					(size 1 1)
					(thickness 0.15)
				)
			)
		)
		(property "Manufacturer" "Vishay"
			(at -34.765 160.105 0)
			(layer "F.Fab")
			(hide yes)
			(effects
				(font
					(size 1 1)
					(thickness 0.15)
				)
			)
		)
		(sheetname "Supply")
		(sheetfile "supply.kicad_sch")
		(attr smd)
		(net_tie_pad_groups "1,2,26" "3,4,27" "5,6,7,8,9")
		(fp_line
			(start -2.11 2.11)
			(end -2.11 1.39)
			(stroke
				(width 0.15)
				(type solid)
			)
			(layer "F.SilkS")
		)
		(fp_line
			(start -1.89 2.11)
			(end -2.11 2.11)
			(stroke
				(width 0.15)
				(type solid)
			)
			(layer "F.SilkS")
		)
		(fp_line
			(start 1.44 2.11)
			(end 2.11 2.11)
			(stroke
				(width 0.15)
				(type solid)
			)
			(layer "F.SilkS")
		)
		(fp_line
			(start 2.11 2.11)
			(end 2.11 1.84)
			(stroke
				(width 0.15)
				(type solid)
			)
			(layer "F.SilkS")
		)
		(fp_line
			(start -2.11 -1.38)
			(end -2.11 -2.1)
			(stroke
				(width 0.15)
				(type solid)
			)
			(layer "F.SilkS")
		)
		(fp_line
			(start -1.89 -2.1)
			(end -2.11 -2.1)
			(stroke
				(width 0.15)
				(type solid)
			)
			(layer "F.SilkS")
		)
		(fp_line
			(start 1.89 -2.11)
			(end 2.11 -2.11)
			(stroke
				(width 0.15)
				(type solid)
			)
			(layer "F.SilkS")
		)
		(fp_line
			(start 2.11 -2.11)
			(end 2.11 -1.69)
			(stroke
				(width 0.15)
				(type solid)
			)
			(layer "F.SilkS")
		)
		(fp_circle
			(center -2.25 -1.15)
			(end -2.2 -1.15)
			(stroke
				(width 0.15)
				(type solid)
			)
			(fill solid)
			(layer "F.SilkS")
		)
		(fp_line
			(start -2.55 2.55)
			(end -2.55 -2.55)
			(stroke
				(width 0.05)
				(type solid)
			)
			(layer "F.CrtYd")
		)
		(fp_line
			(start 2.55 2.55)
			(end -2.55 2.55)
			(stroke
				(width 0.05)
				(type solid)
			)
			(layer "F.CrtYd")
		)
		(fp_line
			(start -2.55 -2.55)
			(end 2.55 -2.55)
			(stroke
				(width 0.05)
				(type solid)
			)
			(layer "F.CrtYd")
		)
		(fp_line
			(start 2.55 -2.55)
			(end 2.55 2.55)
			(stroke
				(width 0.05)
				(type solid)
			)
			(layer "F.CrtYd")
		)
		(fp_line
			(start -2 2)
			(end 2 2)
			(stroke
				(width 0.15)
				(type solid)
			)
			(layer "F.Fab")
		)
		(fp_line
			(start 2 2)
			(end 2 -2)
			(stroke
				(width 0.15)
				(type solid)
			)
			(layer "F.Fab")
		)
		(fp_line
			(start -2 -1)
			(end -2 2)
			(stroke
				(width 0.15)
				(type solid)
			)
			(layer "F.Fab")
		)
		(fp_line
			(start -1 -2)
			(end -2 -1)
			(stroke
				(width 0.15)
				(type solid)
			)
			(layer "F.Fab")
		)
		(fp_line
			(start 2 -2)
			(end -1 -2)
			(stroke
				(width 0.15)
				(type solid)
			)
			(layer "F.Fab")
		)
		(fp_text user "${REFERENCE}"
			(at -2.9 6.8 90)
			(layer "F.Fab")
			(hide yes)
			(effects
				(font
					(size 0.7 0.7)
					(thickness 0.15)
				)
				(justify right bottom)
			)
		)
		(fp_text user "License: Apache-2.0"
			(at -2.7 5.6 -90)
			(layer "F.Fab")
			(hide yes)
			(effects
				(font
					(size 0.7 0.7)
					(thickness 0.15)
				)
				(justify left bottom)
			)
		)
		(fp_text user "License: "
			(at -2.9 5.6 90)
			(layer "F.Fab")
			(hide yes)
			(effects
				(font
					(size 0.7 0.7)
					(thickness 0.15)
				)
				(justify right bottom)
			)
		)
		(fp_text user "Author: Antmicro"
			(at -2.9 8 90)
			(layer "F.Fab")
			(hide yes)
			(effects
				(font
					(size 0.7 0.7)
					(thickness 0.15)
				)
				(justify right bottom)
			)
		)
		(pad "1" smd roundrect
			(at -1.94 -0.825)
			(size 0.3 0.725)
			(layers "F.Cu" "F.Paste" "F.Mask")
			(roundrect_rratio 0.25)
			(net 115 "VCC")
			(pinfunction "V_{IN}")
			(pintype "power_in")
		)
		(pad "2" smd roundrect
			(at -1.94 -0.375)
			(size 0.3 0.725)
			(layers "F.Cu" "F.Paste" "F.Mask")
			(roundrect_rratio 0.25)
			(net 115 "VCC")
			(pinfunction "V_{IN}")
			(pintype "passive")
		)
		(pad "3" smd roundrect
			(at -1.94 0.525)
			(size 0.3 0.725)
			(layers "F.Cu" "F.Paste" "F.Mask")
			(roundrect_rratio 0.25)
			(net 1 "GND")
			(pinfunction "P_{GND}")
			(pintype "passive")
		)
		(pad "4" smd roundrect
			(at -1.94 0.975)
			(size 0.3 0.725)
			(layers "F.Cu" "F.Paste" "F.Mask")
			(roundrect_rratio 0.25)
			(net 1 "GND")
			(pinfunction "P_{GND}")
			(pintype "passive")
		)
		(pad "5" smd custom
			(at -1.475 1.94 270)
			(size 0.3 0.3)
			(layers "F.Cu" "F.Paste" "F.Mask")
			(net 763 "/Supply/5V_SW")
			(pinfunction "SW")
			(pintype "passive")
			(options
				(clearance outline)
				(anchor circle)
			)
			(primitives
				(gr_poly
					(pts
						(xy -0.15 -0.2875) (xy -0.144291 -0.316201) (xy -0.128033 -0.340533) (xy -0.103701 -0.356791)
						(xy -0.075 -0.3625) (xy 0.075 -0.3625) (xy 0.103701 -0.356791) (xy 0.128033 -0.340533) (xy 0.144291 -0.316201)
						(xy 0.15 -0.2875) (xy 0.15 0.2875) (xy 0.144291 0.316201) (xy 0.128033 0.340533) (xy 0.103701 0.356791)
						(xy 0.075 0.3625) (xy -0.075 0.3625) (xy -0.103701 0.356791) (xy -0.128033 0.340533) (xy -0.144291 0.316201)
						(xy -0.15 0.2875)
					)
					(width 0)
					(fill yes)
				)
				(gr_poly
					(pts
						(xy -0.15 -0.3625) (xy 2.2 -0.3625) (xy 2.2 -0.0875) (xy -0.15 -0.0875)
					)
					(width 0)
					(fill yes)
				)
			)
		)
		(pad "6" smd roundrect
			(at -1.025 1.94 270)
			(size 0.3 0.725)
			(layers "F.Cu" "F.Paste" "F.Mask")
			(roundrect_rratio 0.25)
			(net 763 "/Supply/5V_SW")
			(pinfunction "SW")
			(pintype "passive")
		)
		(pad "7" smd roundrect
			(at -0.575 1.94 270)
			(size 0.3 0.725)
			(layers "F.Cu" "F.Paste" "F.Mask")
			(roundrect_rratio 0.25)
			(net 763 "/Supply/5V_SW")
			(pinfunction "SW")
			(pintype "passive")
		)
		(pad "8" smd roundrect
			(at 0.125 1.94 270)
			(size 0.3 0.725)
			(layers "F.Cu" "F.Paste" "F.Mask")
			(roundrect_rratio 0.25)
			(net 763 "/Supply/5V_SW")
			(pinfunction "SW")
			(pintype "passive")
		)
		(pad "9" smd roundrect
			(at 0.575 1.94 270)
			(size 0.3 0.725)
			(layers "F.Cu" "F.Paste" "F.Mask")
			(roundrect_rratio 0.25)
			(net 763 "/Supply/5V_SW")
			(pinfunction "SW")
			(pintype "passive")
		)
		(pad "10" smd roundrect
			(at 1.025 1.935 270)
			(size 0.3 0.725)
			(layers "F.Cu" "F.Paste" "F.Mask")
			(roundrect_rratio 0.25)
			(net 782 "unconnected-(U1-GL-Pad10)_2")
			(pinfunction "GL")
			(pintype "passive+no_connect")
		)
		(pad "11" smd roundrect
			(at 1.94 1.425)
			(size 0.3 0.725)
			(layers "F.Cu" "F.Paste" "F.Mask")
			(roundrect_rratio 0.25)
			(net 781 "unconnected-(U1-GL-Pad10)_1")
			(pinfunction "GL")
			(pintype "passive+no_connect")
		)
		(pad "12" smd roundrect
			(at 1.94 0.975)
			(size 0.3 0.725)
			(layers "F.Cu" "F.Paste" "F.Mask")
			(roundrect_rratio 0.25)
			(net 762 "/Supply/5V_VDRV")
			(pinfunction "V_{DRV}")
			(pintype "passive")
		)
		(pad "13" smd roundrect
			(at 1.94 0.525)
			(size 0.3 0.725)
			(layers "F.Cu" "F.Paste" "F.Mask")
			(roundrect_rratio 0.25)
			(net 1 "GND")
			(pinfunction "P_{GND}")
			(pintype "power_in")
		)
		(pad "14" smd roundrect
			(at 1.94 0.075)
			(size 0.3 0.725)
			(layers "F.Cu" "F.Paste" "F.Mask")
			(roundrect_rratio 0.25)
			(net 770 "unconnected-(U1-P_{GOOD}-Pad14)")
			(pinfunction "P_{GOOD}")
			(pintype "output+no_connect")
		)
		(pad "15" smd roundrect
			(at 1.94 -0.375)
			(size 0.3 0.725)
			(layers "F.Cu" "F.Paste" "F.Mask")
			(roundrect_rratio 0.25)
			(net 759 "/Supply/5V_VDD")
			(pinfunction "V_{DD}")
			(pintype "passive")
		)
		(pad "16" smd roundrect
			(at 1.94 -0.825)
			(size 0.3 0.725)
			(layers "F.Cu" "F.Paste" "F.Mask")
			(roundrect_rratio 0.25)
			(net 1 "GND")
			(pinfunction "A_{GND}")
			(pintype "power_in")
		)
		(pad "17" smd roundrect
			(at 1.94 -1.275)
			(size 0.3 0.725)
			(layers "F.Cu" "F.Paste" "F.Mask")
			(roundrect_rratio 0.25)
			(net 766 "/Supply/5V_FB")
			(pinfunction "FB")
			(pintype "passive")
		)
		(pad "18" smd roundrect
			(at 1.475 -1.94 270)
			(size 0.3 0.725)
			(layers "F.Cu" "F.Paste" "F.Mask")
			(roundrect_rratio 0.25)
			(net 761 "/Supply/5V_OUT")
			(pinfunction "V_{OUT}")
			(pintype "passive")
		)
		(pad "19" smd roundrect
			(at 1.025 -1.94 270)
			(size 0.3 0.725)
			(layers "F.Cu" "F.Paste" "F.Mask")
			(roundrect_rratio 0.25)
			(net 712 "/Supply/5V_EN")
			(pinfunction "EN")
			(pintype "input")
		)
		(pad "20" smd roundrect
			(at 0.575 -1.94 270)
			(size 0.3 0.725)
			(layers "F.Cu" "F.Paste" "F.Mask")
			(roundrect_rratio 0.25)
			(net 767 "/Supply/5V_MODE2")
			(pinfunction "MODE2")
			(pintype "input")
		)
		(pad "21" smd roundrect
			(at 0.125 -1.94 270)
			(size 0.3 0.725)
			(layers "F.Cu" "F.Paste" "F.Mask")
			(roundrect_rratio 0.25)
			(net 764 "/Supply/5V_MODE1")
			(pinfunction "MODE1")
			(pintype "input")
		)
		(pad "22" smd roundrect
			(at -0.575 -1.94 270)
			(size 0.3 0.725)
			(layers "F.Cu" "F.Paste" "F.Mask")
			(roundrect_rratio 0.25)
			(net 115 "VCC")
			(pinfunction "V_{IN}")
			(pintype "passive")
		)
		(pad "23" smd roundrect
			(at -1.025 -1.94 270)
			(size 0.3 0.725)
			(layers "F.Cu" "F.Paste" "F.Mask")
			(roundrect_rratio 0.25)
			(net 760 "/Supply/5V_BOOT")
			(pinfunction "BOOT")
			(pintype "passive")
		)
		(pad "24" smd roundrect
			(at -1.475 -1.94 270)
			(size 0.3 0.725)
			(layers "F.Cu" "F.Paste" "F.Mask")
			(roundrect_rratio 0.25)
			(net 765 "/Supply/5V_PHASE")
			(pinfunction "PHASE")
			(pintype "passive")
		)
		(pad "25" smd rect
			(at 0.49 -0.75 90)
			(size 1.575 1.05)
			(layers "F.Cu" "F.Paste" "F.Mask")
			(net 1 "GND")
			(pinfunction "A_{GND}")
			(pintype "passive")
		)
		(pad "26" smd rect
			(at -1.175 -0.75 90)
			(size 1.15 1.05)
			(layers "F.Cu" "F.Paste" "F.Mask")
			(net 115 "VCC")
			(pinfunction "V_{IN}")
			(pintype "passive")
		)
		(pad "27" smd custom
			(at -0.75 0.775 270)
			(size 1 1)
			(layers "F.Cu" "F.Paste" "F.Mask")
			(net 1 "GND")
			(pinfunction "P_{GND}")
			(pintype "passive")
			(options
				(clearance outline)
				(anchor rect)
			)
			(primitives
				(gr_poly
					(pts
						(xy -1 0.5) (xy -1 -0.7) (xy 1.825 -0.7) (xy 1.825 -0.245) (xy 1.175 -0.245) (xy 1.175 0.5)
					)
					(width 0)
					(fill yes)
				)
			)
		)
		(pad "28" smd rect
			(at 0.985 0.99 90)
			(size 0.58 0.38)
			(layers "F.Cu" "F.Paste" "F.Mask")
			(net 769 "unconnected-(U1-GL-Pad10)")
			(pinfunction "GL")
			(pintype "passive+no_connect")
		)
	)
	(footprint "antmicro-footprints:XSON-8_1x1.95mm_P0.5mm"
		(layer "F.Cu")
		(at 90.6 117 180)
		(property "Reference" "U43"
			(at 0.875 1.175 180)
			(layer "F.SilkS")
			(effects
				(font
					(size 0.7 0.7)
					(thickness 0.15)
				)
				(justify left bottom)
			)
		)
		(property "Value" "NTS0102_XSON"
			(at 0 2.2 180)
			(layer "F.Fab")
			(effects
				(font
					(size 0.7 0.7)
					(thickness 0.15)
				)
				(justify left bottom)
			)
		)
		(property "Footprint" "antmicro-footprints:XSON-8_1x1.95mm_P0.5mm"
			(at 0 0 180)
			(layer "F.Fab")
			(hide yes)
			(effects
				(font
					(size 1.27 1.27)
					(thickness 0.15)
				)
			)
		)
		(property "Datasheet" "http://www.farnell.com/datasheets/1760723.pdf"
			(at 0 0 180)
			(layer "F.Fab")
			(hide yes)
			(effects
				(font
					(size 1.27 1.27)
					(thickness 0.15)
				)
			)
		)
		(property "Author" "Antmicro"
			(at 181.2 234 0)
			(layer "F.Fab")
			(hide yes)
			(effects
				(font
					(size 1 1)
					(thickness 0.15)
				)
			)
		)
		(property "License" "Apache-2.0"
			(at 181.2 234 0)
			(layer "F.Fab")
			(hide yes)
			(effects
				(font
					(size 1 1)
					(thickness 0.15)
				)
			)
		)
		(property "MPN" "NTS0102GT"
			(at 181.2 234 0)
			(layer "F.Fab")
			(hide yes)
			(effects
				(font
					(size 1 1)
					(thickness 0.15)
				)
			)
		)
		(property "Manufacturer" "NXP"
			(at 181.2 234 0)
			(layer "F.Fab")
			(hide yes)
			(effects
				(font
					(size 1 1)
					(thickness 0.15)
				)
			)
		)
		(sheetname "HDMI")
		(sheetfile "hdmi.kicad_sch")
		(attr smd)
		(fp_line
			(start 0.5 1.1)
			(end -0.5 1.1)
			(stroke
				(width 0.15)
				(type solid)
			)
			(layer "F.SilkS")
		)
		(fp_line
			(start -0.5 -1.1)
			(end 0.5 -1.1)
			(stroke
				(width 0.15)
				(type solid)
			)
			(layer "F.SilkS")
		)
		(fp_circle
			(center -0.75 -1.1)
			(end -0.701 -1.1)
			(stroke
				(width 0.15)
				(type solid)
			)
			(fill none)
			(layer "F.SilkS")
		)
		(fp_rect
			(start -0.8 -1.2)
			(end 0.8 1.2)
			(stroke
				(width 0.05)
				(type solid)
			)
			(fill none)
			(layer "F.CrtYd")
		)
		(fp_line
			(start 0.5305 1)
			(end -0.5305 1)
			(stroke
				(width 0.15)
				(type solid)
			)
			(layer "F.Fab")
		)
		(fp_line
			(start 0.5305 -1.001)
			(end 0.5305 1)
			(stroke
				(width 0.15)
				(type solid)
			)
			(layer "F.Fab")
		)
		(fp_line
			(start -0.5305 1)
			(end -0.5305 -1.001)
			(stroke
				(width 0.15)
				(type solid)
			)
			(layer "F.Fab")
		)
		(fp_line
			(start -0.5305 -1.001)
			(end 0.5305 -1.001)
			(stroke
				(width 0.15)
				(type solid)
			)
			(layer "F.Fab")
		)
		(fp_text user "Author: Antmicro"
			(at -0.527 7.105 180)
			(layer "F.Fab")
			(hide yes)
			(effects
				(font
					(size 0.7 0.7)
					(thickness 0.15)
				)
				(justify left bottom)
			)
		)
		(fp_text user "License: Apache-2.0"
			(at -0.527 8.306 180)
			(layer "F.Fab")
			(hide yes)
			(effects
				(font
					(size 0.7 0.7)
					(thickness 0.15)
				)
				(justify left bottom)
			)
		)
		(fp_text user "${REFERENCE}"
			(at -0.527 5.905 180)
			(layer "F.Fab")
			(hide yes)
			(effects
				(font
					(size 0.7 0.7)
					(thickness 0.15)
				)
				(justify left bottom)
			)
		)
		(pad "1" smd roundrect
			(at -0.45 -0.75)
			(size 0.6 0.3)
			(layers "F.Cu" "F.Paste" "F.Mask")
			(roundrect_rratio 0.25)
			(net 519 "/HDMI/HDMI_SCL_5V")
			(pinfunction "B_{2}")
			(pintype "bidirectional")
		)
		(pad "2" smd roundrect
			(at -0.45 -0.25)
			(size 0.6 0.25)
			(layers "F.Cu" "F.Paste" "F.Mask")
			(roundrect_rratio 0.25)
			(net 1 "GND")
			(pinfunction "GND")
			(pintype "power_in")
		)
		(pad "3" smd roundrect
			(at -0.45 0.25)
			(size 0.6 0.25)
			(layers "F.Cu" "F.Paste" "F.Mask")
			(roundrect_rratio 0.25)
			(net 87 "+3V3")
			(pinfunction "VCC_{A}")
			(pintype "power_in")
		)
		(pad "4" smd roundrect
			(at -0.45 0.75)
			(size 0.6 0.3)
			(layers "F.Cu" "F.Paste" "F.Mask")
			(roundrect_rratio 0.25)
			(net 555 "/HDMI/HDMI_SCL_3V3")
			(pinfunction "A_{2}")
			(pintype "bidirectional")
		)
		(pad "5" smd roundrect
			(at 0.45 0.75)
			(size 0.6 0.3)
			(layers "F.Cu" "F.Paste" "F.Mask")
			(roundrect_rratio 0.25)
			(net 701 "/HDMI/HDMI_SDA_3V3")
			(pinfunction "A_{1}")
			(pintype "bidirectional")
		)
		(pad "6" smd roundrect
			(at 0.45 0.25)
			(size 0.6 0.25)
			(layers "F.Cu" "F.Paste" "F.Mask")
			(roundrect_rratio 0.25)
			(net 87 "+3V3")
			(pinfunction "OE")
			(pintype "input")
		)
		(pad "7" smd roundrect
			(at 0.45 -0.25)
			(size 0.6 0.25)
			(layers "F.Cu" "F.Paste" "F.Mask")
			(roundrect_rratio 0.25)
			(net 498 "/HDMI/5V_HDMI")
			(pinfunction "VCC_{B}")
			(pintype "power_in")
		)
		(pad "8" smd roundrect
			(at 0.45 -0.75)
			(size 0.6 0.3)
			(layers "F.Cu" "F.Paste" "F.Mask")
			(roundrect_rratio 0.25)
			(net 518 "/HDMI/HDMI_SDA_5V")
			(pinfunction "B_{1}")
			(pintype "bidirectional")
		)
	)
)
